FILE_TYPE = CONNECTIVITY;
{Allegro Design Entry HDL 17.2-2016 S081 (4005846) 1/11/2022}
"PAGE_NUMBER" = 329;
0"NC";
1"P12V_AUX\g";
2"P12V_AUX\g";
3"P12V_AUX\g";
4"P3V3_AUX\g";
5"P12V_AUX\g";
6"P3V3_AUX\g";
7"P3V3_AUX\g";
8"P12V_AUX\g";
9"P3V3_AUX\g";
10"P3V3_AUX\g";
11"P3V3_AUX\g";
12"P12V_AUX\g";
13"GND\g";
14"GND\g";
15"GND\g";
16"GND\g";
17"GND\g";
18"GND\g";
19"GND\g";
20"GND\g";
21"GND\g";
22"GND\g";
23"GND\g";
24"GND\g";
25"GND\g";
26"GND\g";
27"GND\g";
28"GND\g";
29"GND\g";
30"GND\g";
31"P12V_AUX_UV_TRIGGER";
32"UV_ADR_P2V5_COMP";
33"P12V_AUX_UV_ADR_TRIGGER";
34"IRQ_UV_DETECT_R2_N";
35"UV_P2V5_COMP";
36"FM_UV_ADR_TRIGGER_N_R2";
37"PWRGD_DSW_PWROK_TRIGGER";
38"DSW_PWROK_P2V5_COMP";
39"PWRGD_DSW_PWROK_R5";
40"PWRGD_DSW_PWROK";
41"IRQ_UV_DETECT_N";
42"FM_UV_ADR_TRIGGER_N";
%"Q_CAP"
"1","(-700,2825)","2","pure_quanta","I1";
;
PART_NUMBER"CH4106K1B01"
VALUE"100NF"
VOLTAGE"50V"
TOLERANCE"10%"
PACK_TYPE"C0402"
MATERIAL"EMPTY"
$LOCATION"C2379"
CDS_LIB"pure_quanta"
CDS_LOCATION"C2379"
$SEC"1"
CDS_SEC"1";
"B"
$PN"2"16;
"A"
$PN"1"32;
%"UNIVERSAL_GND"
"1","(325,3650)","0","logical_power","I10";
;
HDL_POWER"GND"
CDS_LIB"logical_power";
"A"13;
%"Q_CAP"
"1","(325,3850)","2","pure_quanta","I11";
;
PART_NUMBER"CH4106K1B01"
VOLTAGE"50V"
PACK_TYPE"C0402"
VALUE"100NF"
TOLERANCE"10%"
MATERIAL"EMPTY"
$LOCATION"C2383"
CDS_LIB"pure_quanta"
CDS_LOCATION"C2383"
$SEC"1"
CDS_SEC"1";
"B"
$PN"2"13;
"A"
$PN"1"3;
%"AP331AWG7"
"1","(75,3225)","0","pure_quanta","I12";
;
PART_NUMBER"AL000331011"
PART_TYPE"SMLF"
VALUE"AP331AWG-7"
MATERIAL"EMPTY"
$LOCATION"U339"
CDS_LIB"pure_quanta"
NEEDS_NO_SIZE"TRUE"
CDS_LMAN_SYM_OUTLINE"-100,100,100,-100"
CDS_LOCATION"U339"
$SEC"1"
CDS_SEC"1";
"GND"
$PN"2"14;
"VCC"
$PN"5"3;
"OUTPUT"
$PN"4"36;
"IN-"
$PN"1"32;
"IN+"
$PN"3"33;
%"UNIVERSAL_GND"
"1","(75,2800)","0","logical_power","I13";
;
CDS_LIB"logical_power"
HDL_POWER"GND";
"A"14;
%"Q_CAP"
"1","(-275,2825)","2","pure_quanta","I14";
;
PART_NUMBER"CH4106K1B01"
VOLTAGE"50V"
VALUE"100NF"
MATERIAL"EMPTY"
TOLERANCE"10%"
PACK_TYPE"C0402"
$LOCATION"C2381"
CDS_LIB"pure_quanta"
CDS_LOCATION"C2381"
$SEC"1"
CDS_SEC"1";
"B"
$PN"2"15;
"A"
$PN"1"33;
%"UNIVERSAL_GND"
"1","(-275,2550)","0","logical_power","I15";
;
CDS_LIB"logical_power"
HDL_POWER"GND";
"A"15;
%"UNIVERSAL_POWER"
"1","(-1100,3750)","0","logical_power","I16";
;
HDL_POWER"P12V_AUX"
CDS_LIB"logical_power";
"A"5;
%"Q_RES"
"2","(-1100,3500)","0","pure_quanta","I17";
;
PART_NUMBER"CS31782FB04"
PACK_TYPE"0402LF"
WATTAGE"1/16W"
TOLERANCE"1%"
VALUE"17.8K"
MATERIAL"EMPTY"
$LOCATION"R4774"
CDS_LIB"pure_quanta"
CDS_LOCATION"R4774"
$SEC"1"
CDS_SEC"1";
"A"
$PN"1"5;
"B"
$PN"2"33;
%"UNIVERSAL_GND"
"1","(-700,2550)","0","logical_power","I18";
;
HDL_POWER"GND"
CDS_LIB"logical_power";
"A"16;
%"UNIVERSAL_GND"
"1","(-1100,2550)","0","logical_power","I19";
;
CDS_LIB"logical_power"
HDL_POWER"GND";
"A"17;
%"Q_RES"
"2","(-1100,2825)","0","pure_quanta","I2";
;
PART_NUMBER"CS25112FB04"
WATTAGE"1/16W"
TOLERANCE"1%"
PACK_TYPE"0402LF"
MATERIAL"EMPTY"
VALUE"5.11K"
$LOCATION"R4775"
CDS_LIB"pure_quanta"
CDS_LOCATION"R4775"
$SEC"1"
CDS_SEC"1";
"A"
$PN"1"33;
"B"
$PN"2"17;
%"UNIVERSAL_POWER"
"1","(-2100,3775)","0","logical_power","I20";
;
HDL_POWER"P3V3_AUX"
CDS_LIB"logical_power";
"A"10;
%"Q_RES"
"2","(-2100,3450)","0","pure_quanta","I21";
;
PART_NUMBER"CS31002FB08"
VALUE"10K"
TOLERANCE"1%"
WATTAGE"1/16W"
MATERIAL"EMPTY"
PACK_TYPE"0402LF"
$LOCATION"R4772"
CDS_LIB"pure_quanta"
CDS_LOCATION"R4772"
$SEC"1"
CDS_SEC"1";
"A"
$PN"1"10;
"B"
$PN"2"32;
%"UNIVERSAL_GND"
"1","(-2075,2300)","0","logical_power","I22";
;
CDS_LIB"logical_power"
HDL_POWER"GND";
"A"18;
%"AP331AWG7"
"1","(100,1100)","0","pure_quanta","I23";
;
PART_NUMBER"AL000331011"
VALUE"AP331AWG-7"
PART_TYPE"SMLF"
MATERIAL"EMPTY"
$LOCATION"U340"
CDS_LIB"pure_quanta"
NEEDS_NO_SIZE"TRUE"
CDS_LMAN_SYM_OUTLINE"-100,100,100,-100"
CDS_LOCATION"U340"
$SEC"1"
CDS_SEC"1";
"GND"
$PN"2"20;
"VCC"
$PN"5"2;
"OUTPUT"
$PN"4"34;
"IN-"
$PN"1"35;
"IN+"
$PN"3"31;
%"UNIVERSAL_POWER"
"1","(2450,1700)","0","logical_power","I24";
;
HDL_POWER"P3V3_AUX"
CDS_LIB"logical_power";
"A"7;
%"Q_RES"
"2","(2450,1375)","0","pure_quanta","I25";
;
PART_NUMBER"CS31002FB08"
TOLERANCE"1%"
WATTAGE"1/16W"
PACK_TYPE"0402LF"
VALUE"10K"
MATERIAL"EMPTY"
$LOCATION"R4785"
CDS_LIB"pure_quanta"
CDS_LOCATION"R4785"
$SEC"1"
CDS_SEC"1";
"A"
$PN"1"7;
"B"
$PN"2"41;
%"Q_RES"
"1","(1475,1100)","0","pure_quanta","I27";
;
PART_NUMBER"CS03322FB03"
TOLERANCE"1%"
VALUE"33.2"
$LOCATION"R4783"
PACK_TYPE"0402LF"
WATTAGE"1/16W"
CDS_LIB"pure_quanta"
MATERIAL"EMPTY"
CDS_LOCATION"R4783"
$SEC"1"
CDS_SEC"1";
"B"
$PN"2"41;
"A"
$PN"1"34;
%"UNIVERSAL_GND"
"1","(350,1525)","0","logical_power","I28";
;
HDL_POWER"GND"
CDS_LIB"logical_power";
"A"19;
%"Q_CAP"
"1","(350,1725)","2","pure_quanta","I29";
;
PART_NUMBER"CH4106K1B01"
PACK_TYPE"C0402"
VALUE"100NF"
VOLTAGE"50V"
TOLERANCE"10%"
MATERIAL"EMPTY"
$LOCATION"C2384"
CDS_LIB"pure_quanta"
CDS_LOCATION"C2384"
$SEC"1"
CDS_SEC"1";
"B"
$PN"2"19;
"A"
$PN"1"2;
%"LM4040AIM3X25NOPB"
"1","(-1700,2625)","0","pure_quanta","I3";
;
PART_NUMBER"AL404025013"
PART_TYPE"SMLF"
VALUE"LM4040AIM3X-2.5/NOPB"
MATERIAL"EMPTY"
$LOCATION"U337"
CDS_LIB"pure_quanta"
PIN_NAMES_ROTATE"True"
CDS_LMAN_SYM_OUTLINE"-200,250,200,-250"
CDS_LOCATION"U337"
$SEC"1"
CDS_SEC"1";
"3"
$PN"3"0;
"2-"
$PN"2"18;
"1+"
$PN"1"32;
%"UNIVERSAL_POWER"
"1","(100,1950)","0","logical_power","I30";
;
HDL_POWER"P12V_AUX"
CDS_LIB"logical_power";
"A"2;
%"Q_RES"
"1","(550,1425)","0","pure_quanta","I31";
;
PART_NUMBER"CS51002FB05"
TOLERANCE"1%"
PACK_TYPE"0402LF"
WATTAGE"1/16W"
VALUE"1M"
MATERIAL"CHIP"
$LOCATION"R4779"
CDS_LIB"pure_quanta"
CDS_LOCATION"R4779"
$SEC"1"
CDS_SEC"1";
"B"
$PN"2"34;
"A"
$PN"1"31;
%"UNIVERSAL_GND"
"1","(100,675)","0","logical_power","I32";
;
CDS_LIB"logical_power"
HDL_POWER"GND";
"A"20;
%"Q_CAP"
"1","(-250,700)","2","pure_quanta","I33";
;
PART_NUMBER"CH4106K1B01"
PACK_TYPE"C0402"
MATERIAL"EMPTY"
VALUE"100NF"
VOLTAGE"50V"
TOLERANCE"10%"
$LOCATION"C2382"
CDS_LIB"pure_quanta"
CDS_LOCATION"C2382"
$SEC"1"
CDS_SEC"1";
"B"
$PN"2"21;
"A"
$PN"1"31;
%"UNIVERSAL_GND"
"1","(-250,425)","0","logical_power","I34";
;
CDS_LIB"logical_power"
HDL_POWER"GND";
"A"21;
%"Q_CAP"
"1","(-675,700)","2","pure_quanta","I35";
;
PART_NUMBER"CH4106K1B01"
TOLERANCE"10%"
MATERIAL"EMPTY"
PACK_TYPE"C0402"
VOLTAGE"50V"
VALUE"100NF"
$LOCATION"C2380"
CDS_LIB"pure_quanta"
CDS_LOCATION"C2380"
$SEC"1"
CDS_SEC"1";
"B"
$PN"2"22;
"A"
$PN"1"35;
%"UNIVERSAL_GND"
"1","(-675,425)","0","logical_power","I36";
;
HDL_POWER"GND"
CDS_LIB"logical_power";
"A"22;
%"UNIVERSAL_POWER"
"1","(-1075,1625)","0","logical_power","I37";
;
HDL_POWER"P12V_AUX"
CDS_LIB"logical_power";
"A"8;
%"Q_RES"
"2","(-1075,1375)","0","pure_quanta","I38";
;
PART_NUMBER"CS31782FB04"
VALUE"17.8K"
TOLERANCE"1%"
WATTAGE"1/16W"
PACK_TYPE"0402LF"
MATERIAL"EMPTY"
$LOCATION"R4776"
CDS_LIB"pure_quanta"
CDS_LOCATION"R4776"
$SEC"1"
CDS_SEC"1";
"A"
$PN"1"8;
"B"
$PN"2"31;
%"Q_RES"
"2","(-1075,700)","0","pure_quanta","I39";
;
PART_NUMBER"CS25112FB04"
PACK_TYPE"0402LF"
VALUE"5.11K"
TOLERANCE"1%"
WATTAGE"1/16W"
MATERIAL"EMPTY"
$LOCATION"R4777"
CDS_LIB"pure_quanta"
CDS_LOCATION"R4777"
$SEC"1"
CDS_SEC"1";
"A"
$PN"1"31;
"B"
$PN"2"23;
%"UNIVERSAL_POWER"
"1","(2425,3825)","0","logical_power","I4";
;
HDL_POWER"P3V3_AUX"
CDS_LIB"logical_power";
"A"4;
%"UNIVERSAL_GND"
"1","(-1075,425)","0","logical_power","I40";
;
CDS_LIB"logical_power"
HDL_POWER"GND";
"A"23;
%"UNIVERSAL_POWER"
"1","(-2075,1650)","0","logical_power","I41";
;
HDL_POWER"P3V3_AUX"
CDS_LIB"logical_power";
"A"11;
%"Q_RES"
"2","(-2075,1325)","0","pure_quanta","I42";
;
PART_NUMBER"CS31002FB08"
TOLERANCE"1%"
VALUE"10K"
WATTAGE"1/16W"
PACK_TYPE"0402LF"
MATERIAL"EMPTY"
$LOCATION"R4773"
CDS_LIB"pure_quanta"
CDS_LOCATION"R4773"
$SEC"1"
CDS_SEC"1";
"A"
$PN"1"11;
"B"
$PN"2"35;
%"LM4040AIM3X25NOPB"
"1","(-1675,500)","0","pure_quanta","I43";
;
PART_NUMBER"AL404025013"
PART_TYPE"SMLF"
VALUE"LM4040AIM3X-2.5/NOPB"
MATERIAL"EMPTY"
$LOCATION"U338"
CDS_LIB"pure_quanta"
PIN_NAMES_ROTATE"True"
CDS_LMAN_SYM_OUTLINE"-200,250,200,-250"
CDS_LOCATION"U338"
$SEC"1"
CDS_SEC"1";
"3"
$PN"3"0;
"2-"
$PN"2"24;
"1+"
$PN"1"35;
%"UNIVERSAL_GND"
"1","(-2050,175)","0","logical_power","I44";
;
CDS_LIB"logical_power"
HDL_POWER"GND";
"A"24;
%"AP331AWG7"
"1","(100,-775)","0","pure_quanta","I45";
;
PART_NUMBER"AL000331011"
MATERIAL"EMPTY"
PART_TYPE"SMLF"
VALUE"AP331AWG-7"
$LOCATION"U342"
CDS_LMAN_SYM_OUTLINE"-100,100,100,-100"
NEEDS_NO_SIZE"TRUE"
CDS_LIB"pure_quanta"
CDS_LOCATION"U342"
$SEC"1"
CDS_SEC"1";
"GND"
$PN"2"29;
"VCC"
$PN"5"12;
"OUTPUT"
$PN"4"39;
"IN-"
$PN"1"38;
"IN+"
$PN"3"37;
%"Q_RES"
"1","(550,-450)","0","pure_quanta","I46";
;
PART_NUMBER"CS51002FB05"
VALUE"1M"
TOLERANCE"1%"
WATTAGE"1/16W"
MATERIAL"EMPTY"
PACK_TYPE"0402LF"
$LOCATION"R4787"
CDS_LIB"pure_quanta"
CDS_LOCATION"R4787"
$SEC"1"
CDS_SEC"1";
"B"
$PN"2"39;
"A"
$PN"1"37;
%"UNIVERSAL_POWER"
"1","(2450,-175)","0","logical_power","I47";
;
HDL_POWER"P3V3_AUX"
CDS_LIB"logical_power";
"A"6;
%"Q_RES"
"2","(2450,-500)","0","pure_quanta","I49";
;
PART_NUMBER"CS31002FB08"
MATERIAL"EMPTY"
VALUE"10K"
PACK_TYPE"0402LF"
WATTAGE"1/16W"
TOLERANCE"1%"
$LOCATION"R4789"
CDS_LIB"pure_quanta"
CDS_LOCATION"R4789"
$SEC"1"
CDS_SEC"1";
"A"
$PN"1"6;
"B"
$PN"2"40;
%"Q_RES"
"1","(1475,-775)","0","pure_quanta","I50";
;
PART_NUMBER"CS03322FB03"
VALUE"33.2"
TOLERANCE"1%"
$LOCATION"R4788"
MATERIAL"EMPTY"
CDS_LIB"pure_quanta"
WATTAGE"1/16W"
PACK_TYPE"0402LF"
CDS_LOCATION"R4788"
$SEC"1"
CDS_SEC"1";
"B"
$PN"2"40;
"A"
$PN"1"39;
%"Q_CAP"
"1","(350,-150)","2","pure_quanta","I51";
;
PART_NUMBER"CH4106K1B01"
PACK_TYPE"C0402"
MATERIAL"EMPTY"
VOLTAGE"50V"
VALUE"100NF"
TOLERANCE"10%"
$LOCATION"C2387"
CDS_LIB"pure_quanta"
CDS_LOCATION"C2387"
$SEC"1"
CDS_SEC"1";
"B"
$PN"2"30;
"A"
$PN"1"12;
%"UNIVERSAL_POWER"
"1","(100,75)","0","logical_power","I52";
;
HDL_POWER"P12V_AUX"
CDS_LIB"logical_power";
"A"12;
%"UNIVERSAL_GND"
"1","(350,-350)","0","logical_power","I53";
;
CDS_LIB"logical_power"
HDL_POWER"GND";
"A"30;
%"UNIVERSAL_GND"
"1","(100,-1200)","0","logical_power","I54";
;
HDL_POWER"GND"
CDS_LIB"logical_power";
"A"29;
%"Q_CAP"
"1","(-250,-1175)","2","pure_quanta","I55";
;
PART_NUMBER"CH4106K1B01"
TOLERANCE"10%"
VOLTAGE"50V"
VALUE"100NF"
MATERIAL"EMPTY"
PACK_TYPE"C0402"
$LOCATION"C2386"
CDS_LIB"pure_quanta"
CDS_LOCATION"C2386"
$SEC"1"
CDS_SEC"1";
"B"
$PN"2"28;
"A"
$PN"1"37;
%"UNIVERSAL_GND"
"1","(-250,-1450)","0","logical_power","I56";
;
HDL_POWER"GND"
CDS_LIB"logical_power";
"A"28;
%"Q_CAP"
"1","(-675,-1175)","2","pure_quanta","I57";
;
PART_NUMBER"CH4106K1B01"
PACK_TYPE"C0402"
VALUE"100NF"
VOLTAGE"50V"
MATERIAL"EMPTY"
TOLERANCE"10%"
$LOCATION"C2385"
CDS_LIB"pure_quanta"
CDS_LOCATION"C2385"
$SEC"1"
CDS_SEC"1";
"B"
$PN"2"27;
"A"
$PN"1"38;
%"UNIVERSAL_GND"
"1","(-675,-1450)","0","logical_power","I58";
;
CDS_LIB"logical_power"
HDL_POWER"GND";
"A"27;
%"UNIVERSAL_POWER"
"1","(-1075,-250)","0","logical_power","I59";
;
HDL_POWER"P12V_AUX"
CDS_LIB"logical_power";
"A"1;
%"Q_RES"
"2","(2425,3500)","0","pure_quanta","I6";
;
PART_NUMBER"CS31002FB08"
TOLERANCE"1%"
WATTAGE"1/16W"
PACK_TYPE"0402LF"
VALUE"10K"
MATERIAL"EMPTY"
$LOCATION"R4784"
CDS_LIB"pure_quanta"
CDS_LOCATION"R4784"
$SEC"1"
CDS_SEC"1";
"A"
$PN"1"4;
"B"
$PN"2"42;
%"UNIVERSAL_GND"
"1","(-1075,-1450)","0","logical_power","I62";
;
HDL_POWER"GND"
CDS_LIB"logical_power";
"A"26;
%"LM4040AIM3X25NOPB"
"1","(-1675,-1375)","0","pure_quanta","I63";
;
PART_NUMBER"AL404025013"
PART_TYPE"SMLF"
MATERIAL"EMPTY"
VALUE"LM4040AIM3X-2.5/NOPB"
$LOCATION"U341"
CDS_LMAN_SYM_OUTLINE"-200,250,200,-250"
PIN_NAMES_ROTATE"True"
CDS_LIB"pure_quanta"
CDS_LOCATION"U341"
$SEC"1"
CDS_SEC"1";
"3"
$PN"3"0;
"2-"
$PN"2"25;
"1+"
$PN"1"38;
%"UNIVERSAL_POWER"
"1","(-2075,-225)","0","logical_power","I64";
;
HDL_POWER"P3V3_AUX"
CDS_LIB"logical_power";
"A"9;
%"Q_RES"
"2","(-2075,-550)","0","pure_quanta","I65";
;
PART_NUMBER"CS31002FB08"
PACK_TYPE"0402LF"
MATERIAL"EMPTY"
WATTAGE"1/16W"
TOLERANCE"1%"
VALUE"10K"
$LOCATION"R4786"
CDS_LIB"pure_quanta"
CDS_LOCATION"R4786"
$SEC"1"
CDS_SEC"1";
"A"
$PN"1"9;
"B"
$PN"2"38;
%"UNIVERSAL_GND"
"1","(-2050,-1700)","0","logical_power","I66";
;
HDL_POWER"GND"
CDS_LIB"logical_power";
"A"25;
%"Q_RES"
"2","(-1075,-500)","0","pure_quanta","I67";
;
PART_NUMBER"CS24752FB03"
VALUE"4.75K"
MATERIAL"EMPTY"
PACK_TYPE"0402LF"
WATTAGE"1/16W"
TOLERANCE"1%"
$LOCATION"R4790"
CDS_LIB"pure_quanta"
CDS_LOCATION"R4790"
$SEC"1"
CDS_SEC"1";
"A"
$PN"1"1;
"B"
$PN"2"37;
%"Q_RES"
"2","(-1075,-1175)","0","pure_quanta","I68";
;
PART_NUMBER"CS22002FB07"
MATERIAL"EMPTY"
VALUE"2K"
PACK_TYPE"0402LF"
WATTAGE"1/16W"
TOLERANCE"1%"
$LOCATION"R4791"
CDS_LIB"pure_quanta"
CDS_LOCATION"R4791"
$SEC"1"
CDS_SEC"1";
"A"
$PN"1"37;
"B"
$PN"2"26;
%"Q_RES"
"1","(1450,3225)","0","pure_quanta","I7";
;
PART_NUMBER"CS03322FB03"
TOLERANCE"1%"
VALUE"33.2"
$LOCATION"R4782"
PACK_TYPE"0402LF"
WATTAGE"1/16W"
CDS_LIB"pure_quanta"
MATERIAL"EMPTY"
CDS_LOCATION"R4782"
$SEC"1"
CDS_SEC"1";
"B"
$PN"2"42;
"A"
$PN"1"36;
%"UNIVERSAL_POWER"
"1","(75,4075)","0","logical_power","I8";
;
HDL_POWER"P12V_AUX"
CDS_LIB"logical_power";
"A"3;
%"Q_RES"
"1","(525,3550)","0","pure_quanta","I9";
;
PART_NUMBER"CS51002FB05"
WATTAGE"1/16W"
VALUE"1M"
MATERIAL"CHIP"
TOLERANCE"1%"
PACK_TYPE"0402LF"
$LOCATION"R4778"
CDS_LIB"pure_quanta"
CDS_LOCATION"R4778"
$SEC"1"
CDS_SEC"1";
"B"
$PN"2"36;
"A"
$PN"1"33;
END.
